(kicad_pcb
	(version 20260206)
	(generator "pcbnew")
	(generator_version "10.0")
	(general
		(thickness 1.6)
		(legacy_teardrops no)
	)
	(paper "A4")
	(title_block
		(title "v1-chassis-manager — T6M_CM_d_v01_1031_1645.brd")
		(comment 1 "Open CloudServer (Microsoft) / footprint 1388 of 2512 (J18), pads 121-164 of 164")
	)
	(layers
		(0 "F.Cu" signal "TOP")
		(4 "In1.Cu" signal "GND1")
		(6 "In2.Cu" signal "IN1")
		(8 "In3.Cu" signal "VCC1")
		(10 "In4.Cu" signal "VCC2")
		(12 "In5.Cu" signal "GND2")
		(14 "In6.Cu" signal "IN2")
		(16 "In7.Cu" signal "IN3")
		(18 "In8.Cu" signal "GND3")
		(2 "B.Cu" signal "BOTTOM")
		(9 "F.Adhes" user "F.Adhesive")
		(11 "B.Adhes" user "B.Adhesive")
		(13 "F.Paste" user "Package Geometry/Pastemask Top")
		(15 "B.Paste" user "Package Geometry/Pastemask Bottom")
		(5 "F.SilkS" user "Ref Des/Silkscreen Top")
		(7 "B.SilkS" user "Ref Des/Silkscreen Bottom")
		(1 "F.Mask" user "Board Geometry/Soldermask Top")
		(3 "B.Mask" user "Board Geometry/Soldermask Bottom")
		(17 "Dwgs.User" user "User.Drawings")
		(19 "Cmts.User" user "User.Comments")
		(21 "Eco1.User" user "User.Eco1")
		(23 "Eco2.User" user "User.Eco2")
		(25 "Edge.Cuts" user "Board Geometry/Outline")
		(27 "Margin" user)
		(31 "F.CrtYd" user "Package Geometry/Place Bound Top")
		(29 "B.CrtYd" user "Package Geometry/Place Bound Bottom")
		(35 "F.Fab" user "Ref Des/Assembly Top")
		(33 "B.Fab" user "Ref Des/Assembly Bottom")
	)
	(footprint ""
		(layer "F.Cu")
		(at 145.515584 -205.199488 180)
		(property "Reference" "J18"
			(at 41.139364 -7.366762 0)
			(unlocked yes)
			(layer "F.SilkS")
			(effects
				(font
					(size 0.7874 0.5842)
					(thickness 0.1524)
				)
				(justify left)
			)
		)
		(property "Value" ""
			(at 0 0 180)
			(layer "F.Fab")
			(effects
				(font
					(size 1.27 1.27)
				)
			)
		)
		(duplicate_pad_numbers_are_jumpers no)
		(pad "B39" smd rect
			(at -1.500124 0 180)
			(size 0.762 4.2164)
			(layers "F.Cu" "F.Mask" "F.Paste")
			(net "UART_T12_NODE2_TXD_R")
		)
		(pad "B40" smd rect
			(at -0.499872 0 180)
			(size 0.762 4.2164)
			(layers "F.Cu" "F.Mask" "F.Paste")
			(net "GND")
		)
		(pad "B41" smd rect
			(at 0.499872 0 180)
			(size 0.762 4.2164)
			(layers "F.Cu" "F.Mask" "F.Paste")
			(net "UART_T12_NODE3_RXD_R")
		)
		(pad "B42" smd rect
			(at 1.500124 0 180)
			(size 0.762 4.2164)
			(layers "F.Cu" "F.Mask" "F.Paste")
			(net "UART_T12_NODE3_TXD_R")
		)
		(pad "B43" smd rect
			(at 2.500122 0 180)
			(size 0.762 4.2164)
			(layers "F.Cu" "F.Mask" "F.Paste")
			(net "UART_T12_NODE4_RXD_R")
		)
		(pad "B44" smd rect
			(at 3.50012 0 180)
			(size 0.762 4.2164)
			(layers "F.Cu" "F.Mask" "F.Paste")
			(net "UART_T12_NODE4_TXD_R")
		)
		(pad "B45" smd rect
			(at 4.500118 0 180)
			(size 0.762 4.2164)
			(layers "F.Cu" "F.Mask" "F.Paste")
			(net "GND")
		)
		(pad "B46" smd rect
			(at 5.500116 0 180)
			(size 0.762 4.2164)
			(layers "F.Cu" "F.Mask" "F.Paste")
			(net "T10_NODE1_EN_R")
		)
		(pad "B47" smd rect
			(at 6.500114 0 180)
			(size 0.762 4.2164)
			(layers "F.Cu" "F.Mask" "F.Paste")
			(net "T10_NODE2_EN_R")
		)
		(pad "B48" smd rect
			(at 7.500112 -0.499872 180)
			(size 0.762 3.2004)
			(layers "F.Cu" "F.Mask" "F.Paste")
			(net "T10_NODE3_EN_R")
		)
		(pad "B49" smd rect
			(at 8.50011 0 180)
			(size 0.762 4.2164)
			(layers "F.Cu" "F.Mask" "F.Paste")
			(net "T10_NODE4_EN_R")
		)
		(pad "B50" smd rect
			(at 9.500108 0 180)
			(size 0.762 4.2164)
			(layers "F.Cu" "F.Mask" "F.Paste")
			(net "GND")
		)
		(pad "B51" smd rect
			(at 10.500106 0 180)
			(size 0.762 4.2164)
			(layers "F.Cu" "F.Mask" "F.Paste")
			(net "UART_T10_NODE1_RXD_R")
		)
		(pad "B52" smd rect
			(at 11.500104 0 180)
			(size 0.762 4.2164)
			(layers "F.Cu" "F.Mask" "F.Paste")
			(net "UART_T10_NODE1_TXD_R")
		)
		(pad "B53" smd rect
			(at 12.500102 0 180)
			(size 0.762 4.2164)
			(layers "F.Cu" "F.Mask" "F.Paste")
			(net "UART_T10_NODE2_RXD_R")
		)
		(pad "B54" smd rect
			(at 13.5001 0 180)
			(size 0.762 4.2164)
			(layers "F.Cu" "F.Mask" "F.Paste")
			(net "UART_T10_NODE2_TXD_R")
		)
		(pad "B55" smd rect
			(at 14.500098 0 180)
			(size 0.762 4.2164)
			(layers "F.Cu" "F.Mask" "F.Paste")
			(net "GND")
		)
		(pad "B56" smd rect
			(at 15.500096 0 180)
			(size 0.762 4.2164)
			(layers "F.Cu" "F.Mask" "F.Paste")
			(net "UART_T10_NODE3_RXD_R")
		)
		(pad "B57" smd rect
			(at 16.500094 0 180)
			(size 0.762 4.2164)
			(layers "F.Cu" "F.Mask" "F.Paste")
			(net "UART_T10_NODE3_TXD_R")
		)
		(pad "B58" smd rect
			(at 17.500092 0 180)
			(size 0.762 4.2164)
			(layers "F.Cu" "F.Mask" "F.Paste")
			(net "UART_T10_NODE4_RXD_R")
		)
		(pad "B59" smd rect
			(at 18.50009 0 180)
			(size 0.762 4.2164)
			(layers "F.Cu" "F.Mask" "F.Paste")
			(net "UART_T10_NODE4_TXD_R")
		)
		(pad "B60" smd rect
			(at 19.500088 0 180)
			(size 0.762 4.2164)
			(layers "F.Cu" "F.Mask" "F.Paste")
			(net "GND")
		)
		(pad "B61" smd rect
			(at 20.500086 0 180)
			(size 0.762 4.2164)
			(layers "F.Cu" "F.Mask" "F.Paste")
			(net "T8_NODE1_EN_R")
		)
		(pad "B62" smd rect
			(at 21.500084 0 180)
			(size 0.762 4.2164)
			(layers "F.Cu" "F.Mask" "F.Paste")
			(net "T8_NODE2_EN_R")
		)
		(pad "B63" smd rect
			(at 22.500082 0 180)
			(size 0.762 4.2164)
			(layers "F.Cu" "F.Mask" "F.Paste")
			(net "T8_NODE3_EN_R")
		)
		(pad "B64" smd rect
			(at 23.50008 0 180)
			(size 0.762 4.2164)
			(layers "F.Cu" "F.Mask" "F.Paste")
			(net "T8_NODE4_EN_R")
		)
		(pad "B65" smd rect
			(at 24.500078 0 180)
			(size 0.762 4.2164)
			(layers "F.Cu" "F.Mask" "F.Paste")
			(net "GND")
		)
		(pad "B66" smd rect
			(at 25.500076 0 180)
			(size 0.762 4.2164)
			(layers "F.Cu" "F.Mask" "F.Paste")
			(net "UART_T8_NODE1_RXD_R")
		)
		(pad "B67" smd rect
			(at 26.500074 0 180)
			(size 0.762 4.2164)
			(layers "F.Cu" "F.Mask" "F.Paste")
			(net "UART_T8_NODE1_TXD_R")
		)
		(pad "B68" smd rect
			(at 27.500072 0 180)
			(size 0.762 4.2164)
			(layers "F.Cu" "F.Mask" "F.Paste")
			(net "UART_T8_NODE2_RXD_R")
		)
		(pad "B69" smd rect
			(at 28.50007 0 180)
			(size 0.762 4.2164)
			(layers "F.Cu" "F.Mask" "F.Paste")
			(net "UART_T8_NODE2_TXD_R")
		)
		(pad "B70" smd rect
			(at 29.500068 0 180)
			(size 0.762 4.2164)
			(layers "F.Cu" "F.Mask" "F.Paste")
			(net "GND")
		)
		(pad "B71" smd rect
			(at 30.500066 0 180)
			(size 0.762 4.2164)
			(layers "F.Cu" "F.Mask" "F.Paste")
			(net "UART_T8_NODE3_RXD_R")
		)
		(pad "B72" smd rect
			(at 31.500064 0 180)
			(size 0.762 4.2164)
			(layers "F.Cu" "F.Mask" "F.Paste")
			(net "UART_T8_NODE3_TXD_R")
		)
		(pad "B73" smd rect
			(at 32.500062 0 180)
			(size 0.762 4.2164)
			(layers "F.Cu" "F.Mask" "F.Paste")
			(net "UART_T8_NODE4_RXD_R")
		)
		(pad "B74" smd rect
			(at 33.50006 0 180)
			(size 0.762 4.2164)
			(layers "F.Cu" "F.Mask" "F.Paste")
			(net "UART_T8_NODE4_TXD_R")
		)
		(pad "B75" smd rect
			(at 34.500058 0 180)
			(size 0.762 4.2164)
			(layers "F.Cu" "F.Mask" "F.Paste")
			(net "GND")
		)
		(pad "B76" smd rect
			(at 35.500056 0 180)
			(size 0.762 4.2164)
			(layers "F.Cu" "F.Mask" "F.Paste")
			(net "T6_NODE1_EN_R")
		)
		(pad "B77" smd rect
			(at 36.500054 0 180)
			(size 0.762 4.2164)
			(layers "F.Cu" "F.Mask" "F.Paste")
			(net "T6_NODE2_EN_R")
		)
		(pad "B78" smd rect
			(at 37.500052 0 180)
			(size 0.762 4.2164)
			(layers "F.Cu" "F.Mask" "F.Paste")
			(net "T6_NODE3_EN_R")
		)
		(pad "B79" smd rect
			(at 38.50005 0 180)
			(size 0.762 4.2164)
			(layers "F.Cu" "F.Mask" "F.Paste")
			(net "T6_NODE4_EN_R")
		)
		(pad "B80" smd rect
			(at 39.500048 0 180)
			(size 0.762 4.2164)
			(layers "F.Cu" "F.Mask" "F.Paste")
			(net "GND")
		)
		(pad "B81" smd rect
			(at 40.500046 -0.499872 180)
			(size 0.762 3.2004)
			(layers "F.Cu" "F.Mask" "F.Paste")
			(net "UART_T6_NODE1_RXD_R")
		)
		(pad "B82" smd rect
			(at 41.500044 0 180)
			(size 0.762 4.2164)
			(layers "F.Cu" "F.Mask" "F.Paste")
			(net "UART_T6_NODE1_TXD_R")
		)
	)
)
